(kicad_pcb
	(version 20260206)
	(generator "pcbnew")
	(generator_version "10.0")
	(general
		(thickness 1.6)
		(legacy_teardrops no)
	)
	(paper "A4")
	(title_block
		(title "03242023_DA0F0TMBIJ0_F0T_Motherboard_J_brd_V01_OCP.brd")
		(comment 1 "Grand Teton / footprints 3243-3247 of 6105")
	)
	(layers
		(0 "F.Cu" signal "TOP")
		(4 "In1.Cu" signal "GND")
		(6 "In2.Cu" signal "IN1")
		(8 "In3.Cu" signal "GND1")
		(10 "In4.Cu" signal "IN2")
		(12 "In5.Cu" signal "GND2")
		(14 "In6.Cu" signal "IN3")
		(16 "In7.Cu" signal "GND3")
		(18 "In8.Cu" signal "VCC")
		(20 "In9.Cu" signal "VCC1")
		(22 "In10.Cu" signal "GND4")
		(24 "In11.Cu" signal "IN4")
		(26 "In12.Cu" signal "GND5")
		(28 "In13.Cu" signal "IN5")
		(30 "In14.Cu" signal "GND6")
		(32 "In15.Cu" signal "IN6")
		(34 "In16.Cu" signal "GND7")
		(2 "B.Cu" signal "BOTTOM")
		(9 "F.Adhes" user "F.Adhesive")
		(11 "B.Adhes" user "B.Adhesive")
		(13 "F.Paste" user "Package Geometry/Pastemask Top")
		(15 "B.Paste" user "Package Geometry/Pastemask Bottom")
		(5 "F.SilkS" user "Ref Des/Silkscreen Top")
		(7 "B.SilkS" user "Ref Des/Silkscreen Bottom")
		(1 "F.Mask" user "Board Geometry/Soldermask Top")
		(3 "B.Mask" user "Board Geometry/Soldermask Bottom")
		(17 "Dwgs.User" user "User.Drawings")
		(19 "Cmts.User" user "User.Comments")
		(21 "Eco1.User" user "User.Eco1")
		(23 "Eco2.User" user "User.Eco2")
		(25 "Edge.Cuts" user "Board Geometry/Outline")
		(27 "Margin" user)
		(31 "F.CrtYd" user "Package Geometry/Place Bound Top")
		(29 "B.CrtYd" user "Package Geometry/Place Bound Bottom")
		(35 "F.Fab" user "Ref Des/Assembly Top")
		(33 "B.Fab" user "Ref Des/Assembly Bottom")
	)
	(footprint ""
		(layer "F.Cu")
		(at 354.261928 -260.364986 -90)
		(property "Reference" "C400"
			(at 0 0 270)
			(layer "F.SilkS")
			(hide yes)
			(effects
				(font
					(size 1.27 1.27)
				)
			)
		)
		(property "Value" ""
			(at 0 0 270)
			(layer "F.Fab")
			(effects
				(font
					(size 1.27 1.27)
				)
			)
		)
		(duplicate_pad_numbers_are_jumpers no)
		(fp_line
			(start -0.7874 0.4064)
			(end -0.7874 -0.4064)
			(stroke
				(width 0.1524)
				(type default)
			)
			(layer "F.SilkS")
		)
		(fp_line
			(start 0.7874 0.4064)
			(end -0.7874 0.4064)
			(stroke
				(width 0.1524)
				(type default)
			)
			(layer "F.SilkS")
		)
		(fp_line
			(start -0.7874 -0.4064)
			(end 0.7874 -0.4064)
			(stroke
				(width 0.1524)
				(type default)
			)
			(layer "F.SilkS")
		)
		(fp_line
			(start 0.7874 -0.4064)
			(end 0.7874 0.4064)
			(stroke
				(width 0.1524)
				(type default)
			)
			(layer "F.SilkS")
		)
		(fp_line
			(start -0.67945 0.3048)
			(end -0.67945 -0.305054)
			(stroke
				(width 0.1)
				(type default)
			)
			(layer "F.Fab")
		)
		(fp_line
			(start -0.12065 0.3048)
			(end -0.67945 0.3048)
			(stroke
				(width 0.1)
				(type default)
			)
			(layer "F.Fab")
		)
		(fp_line
			(start 0.120396 0.3048)
			(end 0.120396 0.2794)
			(stroke
				(width 0.1)
				(type default)
			)
			(layer "F.Fab")
		)
		(fp_line
			(start 0.67945 0.3048)
			(end 0.120396 0.3048)
			(stroke
				(width 0.1)
				(type default)
			)
			(layer "F.Fab")
		)
		(fp_line
			(start -0.12065 0.2794)
			(end -0.12065 0.3048)
			(stroke
				(width 0.1)
				(type default)
			)
			(layer "F.Fab")
		)
		(fp_line
			(start 0.120396 0.2794)
			(end -0.12065 0.2794)
			(stroke
				(width 0.1)
				(type default)
			)
			(layer "F.Fab")
		)
		(fp_line
			(start -0.12065 -0.2794)
			(end 0.12065 -0.2794)
			(stroke
				(width 0.1)
				(type default)
			)
			(layer "F.Fab")
		)
		(fp_line
			(start 0.12065 -0.2794)
			(end 0.12065 -0.3048)
			(stroke
				(width 0.1)
				(type default)
			)
			(layer "F.Fab")
		)
		(fp_line
			(start 0.12065 -0.3048)
			(end 0.67945 -0.3048)
			(stroke
				(width 0.1)
				(type default)
			)
			(layer "F.Fab")
		)
		(fp_line
			(start 0.67945 -0.3048)
			(end 0.67945 0.3048)
			(stroke
				(width 0.1)
				(type default)
			)
			(layer "F.Fab")
		)
		(fp_line
			(start -0.67945 -0.305054)
			(end -0.12065 -0.305054)
			(stroke
				(width 0.1)
				(type default)
			)
			(layer "F.Fab")
		)
		(fp_line
			(start -0.12065 -0.305054)
			(end -0.12065 -0.2794)
			(stroke
				(width 0.1)
				(type default)
			)
			(layer "F.Fab")
		)
		(pad "1" smd circle
			(at -0.40005 0 270)
			(size 0 0)
			(layers "F.Cu" "F.Mask" "F.Paste")
			(net "PVCCFA_EHV_FIVRA_CPU0")
		)
		(pad "2" smd circle
			(at 0.40005 0 270)
			(size 0 0)
			(layers "F.Cu" "F.Mask" "F.Paste")
			(net "GND")
		)
	)
	(footprint ""
		(layer "F.Cu")
		(at 117.526816 -245.634256 -90)
		(property "Reference" "C259"
			(at 0 0 270)
			(layer "F.SilkS")
			(hide yes)
			(effects
				(font
					(size 1.27 1.27)
				)
			)
		)
		(property "Value" ""
			(at 0 0 270)
			(layer "F.Fab")
			(effects
				(font
					(size 1.27 1.27)
				)
			)
		)
		(duplicate_pad_numbers_are_jumpers no)
		(fp_line
			(start -0.7874 0.4064)
			(end -0.7874 -0.4064)
			(stroke
				(width 0.1524)
				(type default)
			)
			(layer "F.SilkS")
		)
		(fp_line
			(start 0.7874 0.4064)
			(end -0.7874 0.4064)
			(stroke
				(width 0.1524)
				(type default)
			)
			(layer "F.SilkS")
		)
		(fp_line
			(start -0.7874 -0.4064)
			(end 0.7874 -0.4064)
			(stroke
				(width 0.1524)
				(type default)
			)
			(layer "F.SilkS")
		)
		(fp_line
			(start 0.7874 -0.4064)
			(end 0.7874 0.4064)
			(stroke
				(width 0.1524)
				(type default)
			)
			(layer "F.SilkS")
		)
		(fp_line
			(start -0.67945 0.3048)
			(end -0.67945 -0.305054)
			(stroke
				(width 0.1)
				(type default)
			)
			(layer "F.Fab")
		)
		(fp_line
			(start -0.12065 0.3048)
			(end -0.67945 0.3048)
			(stroke
				(width 0.1)
				(type default)
			)
			(layer "F.Fab")
		)
		(fp_line
			(start 0.120396 0.3048)
			(end 0.120396 0.2794)
			(stroke
				(width 0.1)
				(type default)
			)
			(layer "F.Fab")
		)
		(fp_line
			(start 0.67945 0.3048)
			(end 0.120396 0.3048)
			(stroke
				(width 0.1)
				(type default)
			)
			(layer "F.Fab")
		)
		(fp_line
			(start -0.12065 0.2794)
			(end -0.12065 0.3048)
			(stroke
				(width 0.1)
				(type default)
			)
			(layer "F.Fab")
		)
		(fp_line
			(start 0.120396 0.2794)
			(end -0.12065 0.2794)
			(stroke
				(width 0.1)
				(type default)
			)
			(layer "F.Fab")
		)
		(fp_line
			(start -0.12065 -0.2794)
			(end 0.12065 -0.2794)
			(stroke
				(width 0.1)
				(type default)
			)
			(layer "F.Fab")
		)
		(fp_line
			(start 0.12065 -0.2794)
			(end 0.12065 -0.3048)
			(stroke
				(width 0.1)
				(type default)
			)
			(layer "F.Fab")
		)
		(fp_line
			(start 0.12065 -0.3048)
			(end 0.67945 -0.3048)
			(stroke
				(width 0.1)
				(type default)
			)
			(layer "F.Fab")
		)
		(fp_line
			(start 0.67945 -0.3048)
			(end 0.67945 0.3048)
			(stroke
				(width 0.1)
				(type default)
			)
			(layer "F.Fab")
		)
		(fp_line
			(start -0.67945 -0.305054)
			(end -0.12065 -0.305054)
			(stroke
				(width 0.1)
				(type default)
			)
			(layer "F.Fab")
		)
		(fp_line
			(start -0.12065 -0.305054)
			(end -0.12065 -0.2794)
			(stroke
				(width 0.1)
				(type default)
			)
			(layer "F.Fab")
		)
		(pad "1" smd circle
			(at -0.40005 0 270)
			(size 0 0)
			(layers "F.Cu" "F.Mask" "F.Paste")
			(net "PVCCIN_CPU1")
		)
		(pad "2" smd circle
			(at 0.40005 0 270)
			(size 0 0)
			(layers "F.Cu" "F.Mask" "F.Paste")
			(net "GND")
		)
	)
	(footprint ""
		(layer "F.Cu")
		(at 457.723748 -114.966496)
		(property "Reference" "U209"
			(at -0.853948 -4.849114 0)
			(unlocked yes)
			(layer "F.SilkS")
			(effects
				(font
					(size 0.7874 0.5842)
					(thickness 0.1524)
				)
				(justify left)
			)
		)
		(property "Value" ""
			(at 0 0 0)
			(layer "F.Fab")
			(effects
				(font
					(size 1.27 1.27)
				)
			)
		)
		(duplicate_pad_numbers_are_jumpers no)
		(fp_line
			(start -2.097532 -3.949954)
			(end -2.097532 3.949954)
			(stroke
				(width 0.1524)
				(type default)
			)
			(layer "F.SilkS")
		)
		(fp_line
			(start -2.097532 3.949954)
			(end 2.097532 3.949954)
			(stroke
				(width 0.1524)
				(type default)
			)
			(layer "F.SilkS")
		)
		(fp_line
			(start -1.409954 -3.949954)
			(end -2.097532 -3.949954)
			(stroke
				(width 0.1524)
				(type default)
			)
			(layer "F.SilkS")
		)
		(fp_line
			(start 0 -2.54)
			(end -1.409954 -3.949954)
			(stroke
				(width 0.1524)
				(type default)
			)
			(layer "F.SilkS")
		)
		(fp_line
			(start 1.409954 -3.949954)
			(end 0 -2.54)
			(stroke
				(width 0.1524)
				(type default)
			)
			(layer "F.SilkS")
		)
		(fp_line
			(start 2.097532 -3.949954)
			(end 1.409954 -3.949954)
			(stroke
				(width 0.1524)
				(type default)
			)
			(layer "F.SilkS")
		)
		(fp_line
			(start 2.097532 3.949954)
			(end 2.097532 -3.949954)
			(stroke
				(width 0.1524)
				(type default)
			)
			(layer "F.SilkS")
		)
		(fp_poly
			(pts
				(xy -4.7498 -4.182872) (xy -4.7498 -3.166872) (xy -3.7338 -3.674872)
			)
			(stroke
				(width 0)
				(type default)
			)
			(fill yes)
			(layer "F.SilkS")
		)
		(fp_line
			(start -2.249932 -3.949954)
			(end -2.249932 3.949954)
			(stroke
				(width 0.1)
				(type default)
			)
			(layer "F.Fab")
		)
		(fp_line
			(start -2.249932 3.949954)
			(end 2.249932 3.949954)
			(stroke
				(width 0.1)
				(type default)
			)
			(layer "F.Fab")
		)
		(fp_line
			(start 2.249932 -3.949954)
			(end -2.249932 -3.949954)
			(stroke
				(width 0.1)
				(type default)
			)
			(layer "F.Fab")
		)
		(fp_line
			(start 2.249932 3.949954)
			(end 2.249932 -3.949954)
			(stroke
				(width 0.1)
				(type default)
			)
			(layer "F.Fab")
		)
		(fp_poly
			(pts
				(xy -4.7498 -4.182872) (xy -4.7498 -3.166872) (xy -3.7338 -3.674872)
			)
			(stroke
				(width 0)
				(type default)
			)
			(fill yes)
			(layer "F.Fab")
		)
		(pad "1" smd rect
			(at -2.925064 -3.674872 270)
			(size 0.6096 1.3716)
			(layers "F.Cu" "F.Mask" "F.Paste")
			(net "FM_SMB_CPU0_ALERT")
		)
		(pad "2" smd rect
			(at -2.925064 -2.925064 270)
			(size 0.4064 1.3716)
			(layers "F.Cu" "F.Mask" "F.Paste")
			(net "PD_SMB_OCP1_HP_ADD1")
		)
		(pad "3" smd rect
			(at -2.925064 -2.275078 270)
			(size 0.4064 1.3716)
			(layers "F.Cu" "F.Mask" "F.Paste")
			(net "PD_SMB_OCP1_HP_ADD2")
		)
		(pad "4" smd rect
			(at -2.925064 -1.625092 270)
			(size 0.4064 1.3716)
			(layers "F.Cu" "F.Mask" "F.Paste")
			(net "TP_PCA9555_0_P00")
		)
		(pad "5" smd rect
			(at -2.925064 -0.975106 270)
			(size 0.4064 1.3716)
			(layers "F.Cu" "F.Mask" "F.Paste")
			(net "TP_PCA9555_0_P01")
		)
		(pad "6" smd rect
			(at -2.925064 -0.32512 270)
			(size 0.4064 1.3716)
			(layers "F.Cu" "F.Mask" "F.Paste")
			(net "HP_OCP_V3_1_EN")
		)
		(pad "7" smd rect
			(at -2.925064 0.32512 270)
			(size 0.4064 1.3716)
			(layers "F.Cu" "F.Mask" "F.Paste")
			(net "HP_LVC3_OCP_V3_1_ATTN_OUT_SW_N")
		)
		(pad "8" smd rect
			(at -2.925064 0.975106 270)
			(size 0.4064 1.3716)
			(layers "F.Cu" "F.Mask" "F.Paste")
			(net "HP_LVC3_OCP_V3_1_PRSNT2_N")
		)
		(pad "9" smd rect
			(at -2.925064 1.625092 270)
			(size 0.4064 1.3716)
			(layers "F.Cu" "F.Mask" "F.Paste")
			(net "TP_PCA9555_0_P5")
		)
		(pad "10" smd rect
			(at -2.925064 2.275078 270)
			(size 0.4064 1.3716)
			(layers "F.Cu" "F.Mask" "F.Paste")
			(net "TP_PCA9555_0_P6")
		)
		(pad "11" smd rect
			(at -2.925064 2.925064 270)
			(size 0.4064 1.3716)
			(layers "F.Cu" "F.Mask" "F.Paste")
			(net "TP_PCA9555_0_P7")
		)
		(pad "12" smd rect
			(at -2.925064 3.674872 270)
			(size 0.6096 1.3716)
			(layers "F.Cu" "F.Mask" "F.Paste")
			(net "GND")
		)
		(pad "13" smd rect
			(at 2.925064 3.674872 270)
			(size 0.6096 1.3716)
			(layers "F.Cu" "F.Mask" "F.Paste")
			(net "TP_PCA9555_0_P10")
		)
		(pad "14" smd rect
			(at 2.925064 2.925064 270)
			(size 0.4064 1.3716)
			(layers "F.Cu" "F.Mask" "F.Paste")
			(net "TP_PCA9555_0_P11")
		)
		(pad "15" smd rect
			(at 2.925064 2.275078 270)
			(size 0.4064 1.3716)
			(layers "F.Cu" "F.Mask" "F.Paste")
			(net "TP_PCA9555_0_P12")
		)
		(pad "16" smd rect
			(at 2.925064 1.625092 270)
			(size 0.4064 1.3716)
			(layers "F.Cu" "F.Mask" "F.Paste")
			(net "TP_PCA9555_0_P13")
		)
		(pad "17" smd rect
			(at 2.925064 0.975106 270)
			(size 0.4064 1.3716)
			(layers "F.Cu" "F.Mask" "F.Paste")
			(net "TP_PCA9555_0_P14")
		)
		(pad "18" smd rect
			(at 2.925064 0.32512 270)
			(size 0.4064 1.3716)
			(layers "F.Cu" "F.Mask" "F.Paste")
			(net "TP_PCA9555_0_P15")
		)
		(pad "19" smd rect
			(at 2.925064 -0.32512 270)
			(size 0.4064 1.3716)
			(layers "F.Cu" "F.Mask" "F.Paste")
			(net "TP_PCA9555_0_P16")
		)
		(pad "20" smd rect
			(at 2.925064 -0.975106 270)
			(size 0.4064 1.3716)
			(layers "F.Cu" "F.Mask" "F.Paste")
			(net "TP_PCA9555_0_P17")
		)
		(pad "21" smd rect
			(at 2.925064 -1.625092 270)
			(size 0.4064 1.3716)
			(layers "F.Cu" "F.Mask" "F.Paste")
			(net "PD_SMB_OCP1_HP_ADD0")
		)
		(pad "22" smd rect
			(at 2.925064 -2.275078 270)
			(size 0.4064 1.3716)
			(layers "F.Cu" "F.Mask" "F.Paste")
			(net "SMB_PEHPCPU0_LVC3_R_SCL")
		)
		(pad "23" smd rect
			(at 2.925064 -2.925064 270)
			(size 0.4064 1.3716)
			(layers "F.Cu" "F.Mask" "F.Paste")
			(net "SMB_PEHPCPU0_LVC3_R_SDA")
		)
		(pad "24" smd rect
			(at 2.925064 -3.674872 270)
			(size 0.6096 1.3716)
			(layers "F.Cu" "F.Mask" "F.Paste")
			(net "P3V3_AUX")
		)
	)
	(footprint ""
		(layer "F.Cu")
		(at 46.828964 -104.279446)
		(property "Reference" "C1768"
			(at 0 0 0)
			(layer "F.SilkS")
			(hide yes)
			(effects
				(font
					(size 1.27 1.27)
				)
			)
		)
		(property "Value" ""
			(at 0 0 0)
			(layer "F.Fab")
			(effects
				(font
					(size 1.27 1.27)
				)
			)
		)
		(duplicate_pad_numbers_are_jumpers no)
		(fp_line
			(start -1.524 -0.762)
			(end 1.524 -0.762)
			(stroke
				(width 0.1524)
				(type default)
			)
			(layer "F.SilkS")
		)
		(fp_line
			(start -1.524 0.762)
			(end -1.524 -0.762)
			(stroke
				(width 0.1524)
				(type default)
			)
			(layer "F.SilkS")
		)
		(fp_line
			(start 1.524 -0.762)
			(end 1.524 0.762)
			(stroke
				(width 0.1524)
				(type default)
			)
			(layer "F.SilkS")
		)
		(fp_line
			(start 1.524 0.762)
			(end -1.524 0.762)
			(stroke
				(width 0.1524)
				(type default)
			)
			(layer "F.SilkS")
		)
		(fp_line
			(start -1.1049 -0.724916)
			(end -1.1049 0.724916)
			(stroke
				(width 0.1)
				(type default)
			)
			(layer "F.Fab")
		)
		(fp_line
			(start -1.1049 0.724916)
			(end 1.1049 0.724916)
			(stroke
				(width 0.1)
				(type default)
			)
			(layer "F.Fab")
		)
		(fp_line
			(start 1.1049 -0.724916)
			(end -1.1049 -0.724916)
			(stroke
				(width 0.1)
				(type default)
			)
			(layer "F.Fab")
		)
		(fp_line
			(start 1.1049 0.724916)
			(end 1.1049 -0.724916)
			(stroke
				(width 0.1)
				(type default)
			)
			(layer "F.Fab")
		)
		(pad "1" smd rect
			(at -0.889 0 180)
			(size 1.016 1.27)
			(layers "F.Cu" "F.Mask" "F.Paste")
			(net "P3V3_MAX11617_VDD")
		)
		(pad "2" smd rect
			(at 0.889 0 180)
			(size 1.016 1.27)
			(layers "F.Cu" "F.Mask" "F.Paste")
			(net "GND")
		)
	)
	(footprint ""
		(layer "F.Cu")
		(at 180.42128 -358.698292)
		(property "Reference" "PR1305"
			(at 0 0 0)
			(layer "F.SilkS")
			(hide yes)
			(effects
				(font
					(size 1.27 1.27)
				)
			)
		)
		(property "Value" ""
			(at 0 0 0)
			(layer "F.Fab")
			(effects
				(font
					(size 1.27 1.27)
				)
			)
		)
		(duplicate_pad_numbers_are_jumpers no)
		(fp_line
			(start -0.7874 -0.4064)
			(end 0.7874 -0.4064)
			(stroke
				(width 0.1524)
				(type default)
			)
			(layer "F.SilkS")
		)
		(fp_line
			(start -0.7874 0.4064)
			(end -0.7874 -0.4064)
			(stroke
				(width 0.1524)
				(type default)
			)
			(layer "F.SilkS")
		)
		(fp_line
			(start 0.7874 -0.4064)
			(end 0.7874 0.4064)
			(stroke
				(width 0.1524)
				(type default)
			)
			(layer "F.SilkS")
		)
		(fp_line
			(start 0.7874 0.4064)
			(end -0.7874 0.4064)
			(stroke
				(width 0.1524)
				(type default)
			)
			(layer "F.SilkS")
		)
		(fp_line
			(start -0.67945 -0.305054)
			(end -0.12065 -0.305054)
			(stroke
				(width 0.1)
				(type default)
			)
			(layer "F.Fab")
		)
		(fp_line
			(start -0.67945 0.3048)
			(end -0.67945 -0.305054)
			(stroke
				(width 0.1)
				(type default)
			)
			(layer "F.Fab")
		)
		(fp_line
			(start -0.12065 -0.305054)
			(end -0.12065 -0.2794)
			(stroke
				(width 0.1)
				(type default)
			)
			(layer "F.Fab")
		)
		(fp_line
			(start -0.12065 -0.2794)
			(end 0.12065 -0.2794)
			(stroke
				(width 0.1)
				(type default)
			)
			(layer "F.Fab")
		)
		(fp_line
			(start -0.12065 0.2794)
			(end -0.12065 0.3048)
			(stroke
				(width 0.1)
				(type default)
			)
			(layer "F.Fab")
		)
		(fp_line
			(start -0.12065 0.3048)
			(end -0.67945 0.3048)
			(stroke
				(width 0.1)
				(type default)
			)
			(layer "F.Fab")
		)
		(fp_line
			(start 0.120396 0.2794)
			(end -0.12065 0.2794)
			(stroke
				(width 0.1)
				(type default)
			)
			(layer "F.Fab")
		)
		(fp_line
			(start 0.120396 0.3048)
			(end 0.120396 0.2794)
			(stroke
				(width 0.1)
				(type default)
			)
			(layer "F.Fab")
		)
		(fp_line
			(start 0.12065 -0.3048)
			(end 0.67945 -0.3048)
			(stroke
				(width 0.1)
				(type default)
			)
			(layer "F.Fab")
		)
		(fp_line
			(start 0.12065 -0.2794)
			(end 0.12065 -0.3048)
			(stroke
				(width 0.1)
				(type default)
			)
			(layer "F.Fab")
		)
		(fp_line
			(start 0.67945 -0.3048)
			(end 0.67945 0.3048)
			(stroke
				(width 0.1)
				(type default)
			)
			(layer "F.Fab")
		)
		(fp_line
			(start 0.67945 0.3048)
			(end 0.120396 0.3048)
			(stroke
				(width 0.1)
				(type default)
			)
			(layer "F.Fab")
		)
		(pad "1" smd circle
			(at -0.40005 0)
			(size 0 0)
			(layers "F.Cu" "F.Mask" "F.Paste")
			(net "PVCCFA_EHV_FIVRA_CPU1_LSET3")
		)
		(pad "2" smd circle
			(at 0.40005 0)
			(size 0 0)
			(layers "F.Cu" "F.Mask" "F.Paste")
			(net "GND")
		)
	)
)
